(kicad_pcb
	(version 20260206)
	(generator "pcbnew")
	(generator_version "10.0")
	(general
		(thickness 1.6)
		(legacy_teardrops no)
	)
	(paper "A4")
	(title_block
		(title "04192023_DAF0TMB3IC0_F0TG_MB_C_brd_V02_OCP.brd")
		(comment 1 "Grand Teton / footprints 4079-4085 of 8354")
	)
	(layers
		(0 "F.Cu" signal "TOP")
		(4 "In1.Cu" signal "GND")
		(6 "In2.Cu" signal "IN1")
		(8 "In3.Cu" signal "GND1")
		(10 "In4.Cu" signal "IN2")
		(12 "In5.Cu" signal "GND2")
		(14 "In6.Cu" signal "IN3")
		(16 "In7.Cu" signal "GND3")
		(18 "In8.Cu" signal "VCC")
		(20 "In9.Cu" signal "VCC1")
		(22 "In10.Cu" signal "GND4")
		(24 "In11.Cu" signal "IN4")
		(26 "In12.Cu" signal "GND5")
		(28 "In13.Cu" signal "IN5")
		(30 "In14.Cu" signal "GND6")
		(32 "In15.Cu" signal "IN6")
		(34 "In16.Cu" signal "GND7")
		(2 "B.Cu" signal "BOTTOM")
		(9 "F.Adhes" user "F.Adhesive")
		(11 "B.Adhes" user "B.Adhesive")
		(13 "F.Paste" user "Package Geometry/Pastemask Top")
		(15 "B.Paste" user "Package Geometry/Pastemask Bottom")
		(5 "F.SilkS" user "Ref Des/Silkscreen Top")
		(7 "B.SilkS" user "Ref Des/Silkscreen Bottom")
		(1 "F.Mask" user "Board Geometry/Soldermask Top")
		(3 "B.Mask" user "Board Geometry/Soldermask Bottom")
		(17 "Dwgs.User" user "User.Drawings")
		(19 "Cmts.User" user "User.Comments")
		(21 "Eco1.User" user "User.Eco1")
		(23 "Eco2.User" user "User.Eco2")
		(25 "Edge.Cuts" user "Board Geometry/Outline")
		(27 "Margin" user)
		(31 "F.CrtYd" user "Package Geometry/Place Bound Top")
		(29 "B.CrtYd" user "Package Geometry/Place Bound Bottom")
		(35 "F.Fab" user "Ref Des/Assembly Top")
		(33 "B.Fab" user "Ref Des/Assembly Bottom")
	)
	(footprint ""
		(layer "F.Cu")
		(at 364.366302 -28.2956 -90)
		(property "Reference" "C364"
			(at 0 0 270)
			(layer "F.SilkS")
			(hide yes)
			(effects
				(font
					(size 1.27 1.27)
				)
			)
		)
		(property "Value" ""
			(at 0 0 270)
			(layer "F.Fab")
			(effects
				(font
					(size 1.27 1.27)
				)
			)
		)
		(duplicate_pad_numbers_are_jumpers no)
		(fp_line
			(start -0.7874 0.4064)
			(end -0.7874 -0.4064)
			(stroke
				(width 0.1524)
				(type default)
			)
			(layer "F.SilkS")
		)
		(fp_line
			(start 0.7874 0.4064)
			(end -0.7874 0.4064)
			(stroke
				(width 0.1524)
				(type default)
			)
			(layer "F.SilkS")
		)
		(fp_line
			(start -0.7874 -0.4064)
			(end 0.7874 -0.4064)
			(stroke
				(width 0.1524)
				(type default)
			)
			(layer "F.SilkS")
		)
		(fp_line
			(start 0.7874 -0.4064)
			(end 0.7874 0.4064)
			(stroke
				(width 0.1524)
				(type default)
			)
			(layer "F.SilkS")
		)
		(fp_line
			(start -0.67945 0.3048)
			(end -0.67945 -0.305054)
			(stroke
				(width 0.1)
				(type default)
			)
			(layer "F.Fab")
		)
		(fp_line
			(start -0.12065 0.3048)
			(end -0.67945 0.3048)
			(stroke
				(width 0.1)
				(type default)
			)
			(layer "F.Fab")
		)
		(fp_line
			(start 0.120396 0.3048)
			(end 0.120396 0.2794)
			(stroke
				(width 0.1)
				(type default)
			)
			(layer "F.Fab")
		)
		(fp_line
			(start 0.67945 0.3048)
			(end 0.120396 0.3048)
			(stroke
				(width 0.1)
				(type default)
			)
			(layer "F.Fab")
		)
		(fp_line
			(start -0.12065 0.2794)
			(end -0.12065 0.3048)
			(stroke
				(width 0.1)
				(type default)
			)
			(layer "F.Fab")
		)
		(fp_line
			(start 0.120396 0.2794)
			(end -0.12065 0.2794)
			(stroke
				(width 0.1)
				(type default)
			)
			(layer "F.Fab")
		)
		(fp_line
			(start -0.12065 -0.2794)
			(end 0.12065 -0.2794)
			(stroke
				(width 0.1)
				(type default)
			)
			(layer "F.Fab")
		)
		(fp_line
			(start 0.12065 -0.2794)
			(end 0.12065 -0.3048)
			(stroke
				(width 0.1)
				(type default)
			)
			(layer "F.Fab")
		)
		(fp_line
			(start 0.12065 -0.3048)
			(end 0.67945 -0.3048)
			(stroke
				(width 0.1)
				(type default)
			)
			(layer "F.Fab")
		)
		(fp_line
			(start 0.67945 -0.3048)
			(end 0.67945 0.3048)
			(stroke
				(width 0.1)
				(type default)
			)
			(layer "F.Fab")
		)
		(fp_line
			(start -0.67945 -0.305054)
			(end -0.12065 -0.305054)
			(stroke
				(width 0.1)
				(type default)
			)
			(layer "F.Fab")
		)
		(fp_line
			(start -0.12065 -0.305054)
			(end -0.12065 -0.2794)
			(stroke
				(width 0.1)
				(type default)
			)
			(layer "F.Fab")
		)
		(pad "1" smd circle
			(at -0.40005 0 270)
			(size 0 0)
			(layers "F.Cu" "F.Mask" "F.Paste")
			(net "UART_CPU0_LVC3_UART0_RX")
		)
		(pad "2" smd circle
			(at 0.40005 0 270)
			(size 0 0)
			(layers "F.Cu" "F.Mask" "F.Paste")
			(net "GND")
		)
	)
	(footprint ""
		(layer "F.Cu")
		(at 161.571686 -57.65165 180)
		(property "Reference" "R3575"
			(at 0 0 180)
			(layer "F.SilkS")
			(hide yes)
			(effects
				(font
					(size 1.27 1.27)
				)
			)
		)
		(property "Value" ""
			(at 0 0 180)
			(layer "F.Fab")
			(effects
				(font
					(size 1.27 1.27)
				)
			)
		)
		(duplicate_pad_numbers_are_jumpers no)
		(fp_line
			(start 0.7874 0.4064)
			(end -0.7874 0.4064)
			(stroke
				(width 0.1524)
				(type default)
			)
			(layer "F.SilkS")
		)
		(fp_line
			(start 0.7874 -0.4064)
			(end 0.7874 0.4064)
			(stroke
				(width 0.1524)
				(type default)
			)
			(layer "F.SilkS")
		)
		(fp_line
			(start -0.7874 0.4064)
			(end -0.7874 -0.4064)
			(stroke
				(width 0.1524)
				(type default)
			)
			(layer "F.SilkS")
		)
		(fp_line
			(start -0.7874 -0.4064)
			(end 0.7874 -0.4064)
			(stroke
				(width 0.1524)
				(type default)
			)
			(layer "F.SilkS")
		)
		(fp_line
			(start 0.67945 0.3048)
			(end 0.120396 0.3048)
			(stroke
				(width 0.1)
				(type default)
			)
			(layer "F.Fab")
		)
		(fp_line
			(start 0.67945 -0.3048)
			(end 0.67945 0.3048)
			(stroke
				(width 0.1)
				(type default)
			)
			(layer "F.Fab")
		)
		(fp_line
			(start 0.12065 -0.2794)
			(end 0.12065 -0.3048)
			(stroke
				(width 0.1)
				(type default)
			)
			(layer "F.Fab")
		)
		(fp_line
			(start 0.12065 -0.3048)
			(end 0.67945 -0.3048)
			(stroke
				(width 0.1)
				(type default)
			)
			(layer "F.Fab")
		)
		(fp_line
			(start 0.120396 0.3048)
			(end 0.120396 0.2794)
			(stroke
				(width 0.1)
				(type default)
			)
			(layer "F.Fab")
		)
		(fp_line
			(start 0.120396 0.2794)
			(end -0.12065 0.2794)
			(stroke
				(width 0.1)
				(type default)
			)
			(layer "F.Fab")
		)
		(fp_line
			(start -0.12065 0.3048)
			(end -0.67945 0.3048)
			(stroke
				(width 0.1)
				(type default)
			)
			(layer "F.Fab")
		)
		(fp_line
			(start -0.12065 0.2794)
			(end -0.12065 0.3048)
			(stroke
				(width 0.1)
				(type default)
			)
			(layer "F.Fab")
		)
		(fp_line
			(start -0.12065 -0.2794)
			(end 0.12065 -0.2794)
			(stroke
				(width 0.1)
				(type default)
			)
			(layer "F.Fab")
		)
		(fp_line
			(start -0.12065 -0.305054)
			(end -0.12065 -0.2794)
			(stroke
				(width 0.1)
				(type default)
			)
			(layer "F.Fab")
		)
		(fp_line
			(start -0.67945 0.3048)
			(end -0.67945 -0.305054)
			(stroke
				(width 0.1)
				(type default)
			)
			(layer "F.Fab")
		)
		(fp_line
			(start -0.67945 -0.305054)
			(end -0.12065 -0.305054)
			(stroke
				(width 0.1)
				(type default)
			)
			(layer "F.Fab")
		)
		(pad "1" smd circle
			(at -0.40005 0 180)
			(size 0 0)
			(layers "F.Cu" "F.Mask" "F.Paste")
			(net "P3V3_M2_0")
		)
		(pad "2" smd circle
			(at 0.40005 0 180)
			(size 0 0)
			(layers "F.Cu" "F.Mask" "F.Paste")
			(net "VSENSE_P12V_INA230_4_INN")
		)
	)
	(footprint ""
		(layer "F.Cu")
		(at 331.37602 -334.971898 -90)
		(property "Reference" "PC81_C1P0_1"
			(at 0 0 270)
			(layer "F.SilkS")
			(hide yes)
			(effects
				(font
					(size 1.27 1.27)
				)
			)
		)
		(property "Value" ""
			(at 0 0 270)
			(layer "F.Fab")
			(effects
				(font
					(size 1.27 1.27)
				)
			)
		)
		(duplicate_pad_numbers_are_jumpers no)
		(fp_line
			(start -0.7874 0.4064)
			(end -0.7874 -0.4064)
			(stroke
				(width 0.1524)
				(type default)
			)
			(layer "F.SilkS")
		)
		(fp_line
			(start 0.7874 0.4064)
			(end -0.7874 0.4064)
			(stroke
				(width 0.1524)
				(type default)
			)
			(layer "F.SilkS")
		)
		(fp_line
			(start -0.7874 -0.4064)
			(end 0.7874 -0.4064)
			(stroke
				(width 0.1524)
				(type default)
			)
			(layer "F.SilkS")
		)
		(fp_line
			(start 0.7874 -0.4064)
			(end 0.7874 0.4064)
			(stroke
				(width 0.1524)
				(type default)
			)
			(layer "F.SilkS")
		)
		(fp_line
			(start -0.67945 0.3048)
			(end -0.67945 -0.305054)
			(stroke
				(width 0.1)
				(type default)
			)
			(layer "F.Fab")
		)
		(fp_line
			(start -0.12065 0.3048)
			(end -0.67945 0.3048)
			(stroke
				(width 0.1)
				(type default)
			)
			(layer "F.Fab")
		)
		(fp_line
			(start 0.120396 0.3048)
			(end 0.120396 0.2794)
			(stroke
				(width 0.1)
				(type default)
			)
			(layer "F.Fab")
		)
		(fp_line
			(start 0.67945 0.3048)
			(end 0.120396 0.3048)
			(stroke
				(width 0.1)
				(type default)
			)
			(layer "F.Fab")
		)
		(fp_line
			(start -0.12065 0.2794)
			(end -0.12065 0.3048)
			(stroke
				(width 0.1)
				(type default)
			)
			(layer "F.Fab")
		)
		(fp_line
			(start 0.120396 0.2794)
			(end -0.12065 0.2794)
			(stroke
				(width 0.1)
				(type default)
			)
			(layer "F.Fab")
		)
		(fp_line
			(start -0.12065 -0.2794)
			(end 0.12065 -0.2794)
			(stroke
				(width 0.1)
				(type default)
			)
			(layer "F.Fab")
		)
		(fp_line
			(start 0.12065 -0.2794)
			(end 0.12065 -0.3048)
			(stroke
				(width 0.1)
				(type default)
			)
			(layer "F.Fab")
		)
		(fp_line
			(start 0.12065 -0.3048)
			(end 0.67945 -0.3048)
			(stroke
				(width 0.1)
				(type default)
			)
			(layer "F.Fab")
		)
		(fp_line
			(start 0.67945 -0.3048)
			(end 0.67945 0.3048)
			(stroke
				(width 0.1)
				(type default)
			)
			(layer "F.Fab")
		)
		(fp_line
			(start -0.67945 -0.305054)
			(end -0.12065 -0.305054)
			(stroke
				(width 0.1)
				(type default)
			)
			(layer "F.Fab")
		)
		(fp_line
			(start -0.12065 -0.305054)
			(end -0.12065 -0.2794)
			(stroke
				(width 0.1)
				(type default)
			)
			(layer "F.Fab")
		)
		(pad "1" smd circle
			(at -0.40005 0 270)
			(size 0 0)
			(layers "F.Cu" "F.Mask" "F.Paste")
			(net "PVDDCR_CPU1_P0_PVCC")
		)
		(pad "2" smd circle
			(at 0.40005 0 270)
			(size 0 0)
			(layers "F.Cu" "F.Mask" "F.Paste")
			(net "GND")
		)
	)
	(footprint ""
		(layer "F.Cu")
		(at 316.15761 137.70356 90)
		(property "Reference" "ME5"
			(at 0.0254 -3.851148 90)
			(unlocked yes)
			(layer "F.SilkS")
			(effects
				(font
					(size 0.7874 0.5842)
					(thickness 0.1524)
				)
				(justify left)
			)
		)
		(property "Value" ""
			(at 0 0 90)
			(layer "F.Fab")
			(effects
				(font
					(size 1.27 1.27)
				)
			)
		)
		(duplicate_pad_numbers_are_jumpers no)
	)
	(footprint ""
		(layer "F.Cu")
		(at 498.693948 -142.844266 90)
		(property "Reference" "X8003"
			(at -1.975358 1.637792 0)
			(unlocked yes)
			(layer "F.SilkS")
			(effects
				(font
					(size 0.7874 0.5842)
					(thickness 0.1524)
				)
				(justify left)
			)
		)
		(property "Value" ""
			(at 0 0 90)
			(layer "F.Fab")
			(effects
				(font
					(size 1.27 1.27)
				)
			)
		)
		(property "Device Type" "TP_TDR_4P_FTS_TH-TP_TDR_4P_DIP,EMPTY,TP15"
			(at 1.30175 1.27 180)
			(unlocked yes)
			(layer "F.Fab")
			(hide yes)
			(effects
				(font
					(size 0.635 0.4064)
					(thickness 0.1524)
				)
			)
		)
		(property "User Part Number" "N_A"
			(at 1.30175 1.27 180)
			(unlocked yes)
			(layer "Cmts.User")
			(hide yes)
			(effects
				(font
					(size 0.635 0.4064)
					(thickness 0.1524)
				)
			)
		)
		(duplicate_pad_numbers_are_jumpers no)
		(fp_line
			(start 2.54 -1.27)
			(end 0 -1.27)
			(stroke
				(width 0.1524)
				(type default)
			)
			(layer "F.SilkS")
		)
		(fp_line
			(start 0 -1.27)
			(end 0 -0.635)
			(stroke
				(width 0.1524)
				(type default)
			)
			(layer "F.SilkS")
		)
		(fp_line
			(start 2.54 -1.1303)
			(end 2.54 -1.27)
			(stroke
				(width 0.1524)
				(type default)
			)
			(layer "F.SilkS")
		)
		(fp_line
			(start 0 0.635)
			(end 0 1.905)
			(stroke
				(width 0.1524)
				(type default)
			)
			(layer "F.SilkS")
		)
		(fp_line
			(start 2.54 1.4097)
			(end 2.54 1.1303)
			(stroke
				(width 0.1524)
				(type default)
			)
			(layer "F.SilkS")
		)
		(fp_line
			(start 0 3.175)
			(end 0 3.81)
			(stroke
				(width 0.1524)
				(type default)
			)
			(layer "F.SilkS")
		)
		(fp_line
			(start 2.54 3.81)
			(end 2.54 3.6703)
			(stroke
				(width 0.1524)
				(type default)
			)
			(layer "F.SilkS")
		)
		(fp_line
			(start 0 3.81)
			(end 2.54 3.81)
			(stroke
				(width 0.1524)
				(type default)
			)
			(layer "F.SilkS")
		)
		(fp_poly
			(pts
				(xy -2.285746 -0.762) (xy -0.761746 0) (xy -2.285746 0.762)
			)
			(stroke
				(width 0)
				(type default)
			)
			(fill yes)
			(layer "F.SilkS")
		)
		(fp_line
			(start 2.54 -1.27)
			(end 0 -1.27)
			(stroke
				(width 0.1)
				(type default)
			)
			(layer "F.Fab")
		)
		(fp_line
			(start 0 -1.27)
			(end 0 3.81)
			(stroke
				(width 0.1)
				(type default)
			)
			(layer "F.Fab")
		)
		(fp_line
			(start 2.54 3.81)
			(end 2.54 -1.27)
			(stroke
				(width 0.1)
				(type default)
			)
			(layer "F.Fab")
		)
		(fp_line
			(start 0 3.81)
			(end 2.54 3.81)
			(stroke
				(width 0.1)
				(type default)
			)
			(layer "F.Fab")
		)
		(fp_poly
			(pts
				(xy -0.761746 0) (xy -2.285746 -0.762) (xy -2.285746 0.762)
			)
			(stroke
				(width 0)
				(type default)
			)
			(fill yes)
			(layer "F.Fab")
		)
		(pad "1" thru_hole circle
			(at 0 0 90)
			(size 1.0033 1.0033)
			(drill 0.249936)
			(layers "*.Cu" "*.Mask")
			(remove_unused_layers no)
			(net "TDR_DIFF_85_IN2_DP")
			(clearance 0.10795)
			(thermal_gap 0.10795)
			(padstack
				(mode front_inner_back)
				(layer "Inner"
					(shape circle)
					(size 0.8001 0.8001)
					(clearance 0.1524)
				)
				(layer "B.Cu"
					(shape circle)
					(size 1.0033 1.0033)
					(clearance 0.10795)
				)
			)
		)
		(pad "2" thru_hole circle
			(at 2.54 0 90)
			(size 1.9939 1.9939)
			(drill 0.249936)
			(layers "*.Cu" "*.Mask")
			(remove_unused_layers no)
			(net "T1_GND")
			(clearance 0.10795)
			(thermal_gap 0.10795)
			(padstack
				(mode front_inner_back)
				(layer "Inner"
					(shape circle)
					(size 0.8001 0.8001)
					(clearance 0.1524)
				)
				(layer "B.Cu"
					(shape circle)
					(size 1.9939 1.9939)
					(clearance 0.10795)
				)
			)
		)
		(pad "3" thru_hole circle
			(at 2.54 2.54 90)
			(size 1.9939 1.9939)
			(drill 0.249936)
			(layers "*.Cu" "*.Mask")
			(remove_unused_layers no)
			(net "T1_GND")
			(clearance 0.10795)
			(thermal_gap 0.10795)
			(padstack
				(mode front_inner_back)
				(layer "Inner"
					(shape circle)
					(size 0.8001 0.8001)
					(clearance 0.1524)
				)
				(layer "B.Cu"
					(shape circle)
					(size 1.9939 1.9939)
					(clearance 0.10795)
				)
			)
		)
		(pad "4" thru_hole circle
			(at 0 2.54 90)
			(size 1.0033 1.0033)
			(drill 0.249936)
			(layers "*.Cu" "*.Mask")
			(remove_unused_layers no)
			(net "TDR_DIFF_85_IN2_DN")
			(clearance 0.10795)
			(thermal_gap 0.10795)
			(padstack
				(mode front_inner_back)
				(layer "Inner"
					(shape circle)
					(size 0.8001 0.8001)
					(clearance 0.1524)
				)
				(layer "B.Cu"
					(shape circle)
					(size 1.0033 1.0033)
					(clearance 0.10795)
				)
			)
		)
	)
	(footprint ""
		(layer "F.Cu")
		(at 330.63434 -16.178276 90)
		(property "Reference" "D7"
			(at -3.12166 0.79375 90)
			(unlocked yes)
			(layer "F.SilkS")
			(effects
				(font
					(size 0.7874 0.5842)
					(thickness 0.1524)
				)
				(justify left)
			)
		)
		(property "Value" ""
			(at 0 0 90)
			(layer "F.Fab")
			(effects
				(font
					(size 1.27 1.27)
				)
			)
		)
		(duplicate_pad_numbers_are_jumpers no)
		(fp_line
			(start 1.778 -0.5588)
			(end 1.3208 -0.5588)
			(stroke
				(width 0.1524)
				(type default)
			)
			(layer "F.SilkS")
		)
		(fp_line
			(start 1.778 -0.5588)
			(end 1.778 0.5588)
			(stroke
				(width 0.1524)
				(type default)
			)
			(layer "F.SilkS")
		)
		(fp_line
			(start 1.4732 -0.5588)
			(end 1.4732 0.5588)
			(stroke
				(width 0.1524)
				(type default)
			)
			(layer "F.SilkS")
		)
		(fp_line
			(start 1.3208 -0.5588)
			(end 1.3208 0.5588)
			(stroke
				(width 0.1524)
				(type default)
			)
			(layer "F.SilkS")
		)
		(fp_line
			(start -1.3208 -0.5588)
			(end 1.3208 -0.5588)
			(stroke
				(width 0.1524)
				(type default)
			)
			(layer "F.SilkS")
		)
		(fp_line
			(start 1.778 0.5588)
			(end 1.3208 0.5588)
			(stroke
				(width 0.1524)
				(type default)
			)
			(layer "F.SilkS")
		)
		(fp_line
			(start 1.6256 0.5588)
			(end 1.6256 -0.5588)
			(stroke
				(width 0.1524)
				(type default)
			)
			(layer "F.SilkS")
		)
		(fp_line
			(start 1.3208 0.5588)
			(end -1.3208 0.5588)
			(stroke
				(width 0.1524)
				(type default)
			)
			(layer "F.SilkS")
		)
		(fp_line
			(start -1.3208 0.5588)
			(end -1.3208 -0.5588)
			(stroke
				(width 0.1524)
				(type default)
			)
			(layer "F.SilkS")
		)
		(fp_line
			(start 0.899922 -0.40005)
			(end 0.899922 0.40005)
			(stroke
				(width 0.1)
				(type default)
			)
			(layer "F.Fab")
		)
		(fp_line
			(start -0.899922 -0.40005)
			(end 0.899922 -0.40005)
			(stroke
				(width 0.1)
				(type default)
			)
			(layer "F.Fab")
		)
		(fp_line
			(start 0.899922 0.40005)
			(end -0.899922 0.40005)
			(stroke
				(width 0.1)
				(type default)
			)
			(layer "F.Fab")
		)
		(fp_line
			(start -0.899922 0.40005)
			(end -0.899922 -0.40005)
			(stroke
				(width 0.1)
				(type default)
			)
			(layer "F.Fab")
		)
		(fp_text user "-"
			(at 1.651 -0.96901 90)
			(unlocked yes)
			(layer "F.SilkS")
			(effects
				(font
					(size 1.905 1.4224)
					(thickness 0.1524)
				)
				(justify left)
			)
		)
		(fp_text user "+"
			(at -2.57302 -0.59055 90)
			(unlocked yes)
			(layer "F.SilkS")
			(effects
				(font
					(size 1.905 1.4224)
					(thickness 0.1524)
				)
				(justify left)
			)
		)
		(fp_text user "-"
			(at 1.651 -0.22225 90)
			(unlocked yes)
			(layer "F.Fab")
			(effects
				(font
					(size 1.905 1.4224)
					(thickness 0.1524)
				)
				(justify left)
			)
		)
		(fp_text user "+"
			(at -2.6162 -0.22225 90)
			(unlocked yes)
			(layer "F.Fab")
			(effects
				(font
					(size 1.905 1.4224)
					(thickness 0.1524)
				)
				(justify left)
			)
		)
		(pad "A" smd rect
			(at -0.750062 0 90)
			(size 0.8128 0.8128)
			(layers "F.Cu" "F.Mask" "F.Paste")
			(net "BMC_FPGA_LED2_R_N")
		)
		(pad "C" smd rect
			(at 0.750062 0 90)
			(size 0.8128 0.8128)
			(layers "F.Cu" "F.Mask" "F.Paste")
			(net "BMC_FPGA_LED2_N")
		)
	)
	(footprint ""
		(layer "F.Cu")
		(at 330.932536 -387.350254)
		(property "Reference" "R676"
			(at 0 0 0)
			(layer "F.SilkS")
			(hide yes)
			(effects
				(font
					(size 1.27 1.27)
				)
			)
		)
		(property "Value" ""
			(at 0 0 0)
			(layer "F.Fab")
			(effects
				(font
					(size 1.27 1.27)
				)
			)
		)
		(duplicate_pad_numbers_are_jumpers no)
		(fp_line
			(start -0.32512 -0.175006)
			(end 0.32512 -0.175006)
			(stroke
				(width 0.1)
				(type default)
			)
			(layer "F.Fab")
		)
		(fp_line
			(start -0.32512 0.175006)
			(end -0.32512 -0.175006)
			(stroke
				(width 0.1)
				(type default)
			)
			(layer "F.Fab")
		)
		(fp_line
			(start 0.32512 -0.175006)
			(end 0.32512 0.175006)
			(stroke
				(width 0.1)
				(type default)
			)
			(layer "F.Fab")
		)
		(fp_line
			(start 0.32512 0.175006)
			(end -0.32512 0.175006)
			(stroke
				(width 0.1)
				(type default)
			)
			(layer "F.Fab")
		)
		(pad "1" smd rect
			(at -0.2667 0)
			(size 0.3048 0.381)
			(layers "F.Cu" "F.Mask" "F.Paste")
			(net "SMB_RT_CPU0_P1_ROM_MUX_1D_SCL")
		)
		(pad "2" smd rect
			(at 0.2667 0 180)
			(size 0.3048 0.381)
			(layers "F.Cu" "F.Mask" "F.Paste")
			(net "SMB_RT_CPU0_P1_ROM_MUX_1D_R_SCL")
		)
	)
)
